FILE_TYPE = MACRO_DRAWING;
SET COLOR_WIRE YELLOW;
SET COLOR_PROP MONO;
SET COLOR_DOT WHITE;
SET COLOR_ARC YELLOW;
SET COLOR_BODY GREEN;
SET COLOR_NOTE MONO;
SET PROP_DISPLAY VALUE;
SET PAGE_NUMBER P128;
FORCEADD INTEL_CORP_BPAGE..1
(10400 700);
FORCEPROP 1 LAST CUSTOM_TXT_CDS <CURRENT_DESIGN_SHEET> OF <TOTAL_DESIGN_SHEETS>
J 0
(9900 725);
PAINT GREEN (9900 725);
FORCEPROP 2 LAST CUSTOM_TXT_CDS <XR_PAGE_TITLE>
J 0
(2510 5950);
DISPLAY 0.638298 (2510 5950);
PAINT PINK (2510 5950);
DISPLAY INVISIBLE (2510 5950);
FORCEPROP 2 LAST CUSTOM_TXT_CDS <CON_LAST_MODIFIED>
J 0
(8475 1050);
DISPLAY 1.361702 (8475 1050);
PAINT GREEN (8475 1050);
FORCEPROP 1 LAST SCH_ADDRESS3 Santa Clara, CA 95052-8119
J 0
(6425 725);
DISPLAY 0.617021 (6425 725);
PAINT GREEN (6425 725);
FORCEPROP 1 LAST SCH_ADDRESS2 P.O. BOX 58119
J 0
(6425 775);
DISPLAY 0.617021 (6425 775);
PAINT GREEN (6425 775);
FORCEPROP 1 LAST SCH_ADDRESS1 2200 Mission College Blvd.
J 0
(6425 825);
DISPLAY 0.617021 (6425 825);
PAINT GREEN (6425 825);
FORCEPROP 1 LAST SCH_TITLE SPARE
J 0
(2450 750);
DISPLAY 1.212766 (2450 750);
PAINT ORANGE (2450 750);
FORCEPROP 1 LAST SCH_NUMBER H4694802
J 0
(9100 850);
DISPLAY 1.212766 (9100 850);
PAINT YELLOW (9100 850);
FORCEPROP 1 LAST SCH_DEPT BESD
J 1
(5950 800);
DISPLAY 1.212766 (5950 800);
PAINT YELLOW (5950 800);
FORCEPROP 1 LAST SCH_REV 2.420
J 0
(10150 850);
DISPLAY 0.978723 (10150 850);
PAINT YELLOW (10150 850);
FORCEPROP 2 LAST PAGE_BORDER TRUE
J 0
(2510 5950);
DISPLAY 0.851064 (2510 5950);
PAINT PINK (2510 5950);
DISPLAY INVISIBLE (2510 5950);
FORCEPROP 2 LAST CDS_LIB mstr_symbols
J 0
(10400 700);
DISPLAY 1.361702 (10400 700);
PAINT MONO (10400 700);
DISPLAY INVISIBLE (10400 700);
FORCEPROP 1 LAST COMMENT_BODY TRUE
J 0
(10412 712);
DISPLAY 0.617021 (10412 712);
PAINT GREEN (10412 712);
DISPLAY INVISIBLE (10412 712);
FORCEPROP 1 LAST CDS_CON_LAST_MODIFIED Tue Dec 01 11:48:43 2015
J 0
(8975 1025);
DISPLAY 1.361702 (8975 1025);
PAINT ORANGE (8975 1025);
DISPLAY INVISIBLE (8975 1025);
FORCEPROP 2 LAST CDS_XR_PAGE_TITLE CR-128 : @BASEBOARD_FAB2_LIB.BASEBOARD_FAB2(SCH_1):PAGE128
J 0
(2510 5950);
DISPLAY 0.638298 (2510 5950);
PAINT PINK (2510 5950);
DISPLAY INVISIBLE (2510 5950);
QUIT
